# S9S_MB_2U (Grand Teton) — schematic netlist excerpt (pin names and nets, part order shuffled) for the footprints in the layout excerpt that follows; sources: Cadence DE-HDL packaged netlist, KiCad conversion of 03242023_DA0F0TMBIJ0_F0T_Motherboard_J_brd_V01_OCP.brd

R4796  Q_RES  10K 1% EMPTY  pkg 0402LF  page 306 : A = HSC_OC_VOL ; B = GND
PL20  Q_INDUCTOR  300NH/33A IND  pkg SMLF  page 294 : \1\ = SW_PVCCFA_EHV_CPU1_SW1 ; \2\ = PVCCFA_EHV_CPU1
R3723  Q_RES  2.2K 5% CHIP  pkg 0402LF  page 233 : A = P3V3_AUX ; B = SMB_VR_3V3AUX_SCL

(kicad_pcb
	(version 20260206)
	(generator "pcbnew")
	(generator_version "10.0")
	(general
		(thickness 1.6)
		(legacy_teardrops no)
	)
	(paper "A4")
	(title_block
		(title "03242023_DA0F0TMBIJ0_F0T_Motherboard_J_brd_V01_OCP.brd")
		(comment 1 "Grand Teton / footprints 456-458 of 6105")
	)
	(layers
		(0 "F.Cu" signal "TOP")
		(4 "In1.Cu" signal "GND")
		(6 "In2.Cu" signal "IN1")
		(8 "In3.Cu" signal "GND1")
		(10 "In4.Cu" signal "IN2")
		(12 "In5.Cu" signal "GND2")
		(14 "In6.Cu" signal "IN3")
		(16 "In7.Cu" signal "GND3")
		(18 "In8.Cu" signal "VCC")
		(20 "In9.Cu" signal "VCC1")
		(22 "In10.Cu" signal "GND4")
		(24 "In11.Cu" signal "IN4")
		(26 "In12.Cu" signal "GND5")
		(28 "In13.Cu" signal "IN5")
		(30 "In14.Cu" signal "GND6")
		(32 "In15.Cu" signal "IN6")
		(34 "In16.Cu" signal "GND7")
		(2 "B.Cu" signal "BOTTOM")
		(9 "F.Adhes" user "F.Adhesive")
		(11 "B.Adhes" user "B.Adhesive")
		(13 "F.Paste" user "Package Geometry/Pastemask Top")
		(15 "B.Paste" user "Package Geometry/Pastemask Bottom")
		(5 "F.SilkS" user "Ref Des/Silkscreen Top")
		(7 "B.SilkS" user "Ref Des/Silkscreen Bottom")
		(1 "F.Mask" user "Board Geometry/Soldermask Top")
		(3 "B.Mask" user "Board Geometry/Soldermask Bottom")
		(17 "Dwgs.User" user "User.Drawings")
		(19 "Cmts.User" user "User.Comments")
		(21 "Eco1.User" user "User.Eco1")
		(23 "Eco2.User" user "User.Eco2")
		(25 "Edge.Cuts" user "Board Geometry/Outline")
		(27 "Margin" user)
		(31 "F.CrtYd" user "Package Geometry/Place Bound Top")
		(29 "B.CrtYd" user "Package Geometry/Place Bound Bottom")
		(35 "F.Fab" user "Ref Des/Assembly Top")
		(33 "B.Fab" user "Ref Des/Assembly Bottom")
	)
	(footprint ""
		(layer "F.Cu")
		(at 61.475366 -174.230792)
		(property "Reference" "PL20"
			(at -6.598666 -4.515358 0)
			(unlocked yes)
			(layer "F.SilkS")
			(effects
				(font
					(size 0.7874 0.5842)
					(thickness 0.1524)
				)
				(justify left)
			)
		)
		(property "Value" ""
			(at 0 0 0)
			(layer "F.Fab")
			(effects
				(font
					(size 1.27 1.27)
				)
			)
		)
		(duplicate_pad_numbers_are_jumpers no)
		(fp_line
			(start -4.800092 -3.199892)
			(end 4.800092 -3.199892)
			(stroke
				(width 0.1524)
				(type default)
			)
			(layer "F.SilkS")
		)
		(fp_line
			(start -4.800092 -1.6891)
			(end -4.800092 -3.199892)
			(stroke
				(width 0.1524)
				(type default)
			)
			(layer "F.SilkS")
		)
		(fp_line
			(start -4.800092 3.199892)
			(end -4.800092 1.6891)
			(stroke
				(width 0.1524)
				(type default)
			)
			(layer "F.SilkS")
		)
		(fp_line
			(start 4.800092 -3.199892)
			(end 4.800092 -1.6891)
			(stroke
				(width 0.1524)
				(type default)
			)
			(layer "F.SilkS")
		)
		(fp_line
			(start 4.800092 1.6891)
			(end 4.800092 3.199892)
			(stroke
				(width 0.1524)
				(type default)
			)
			(layer "F.SilkS")
		)
		(fp_line
			(start 4.800092 3.199892)
			(end -4.800092 3.199892)
			(stroke
				(width 0.1524)
				(type default)
			)
			(layer "F.SilkS")
		)
		(fp_line
			(start -4.800092 -3.199892)
			(end 4.800092 -3.199892)
			(stroke
				(width 0.1)
				(type default)
			)
			(layer "F.Fab")
		)
		(fp_line
			(start -4.800092 3.199892)
			(end -4.800092 -3.199892)
			(stroke
				(width 0.1)
				(type default)
			)
			(layer "F.Fab")
		)
		(fp_line
			(start 4.800092 -3.199892)
			(end 4.800092 3.199892)
			(stroke
				(width 0.1)
				(type default)
			)
			(layer "F.Fab")
		)
		(fp_line
			(start 4.800092 3.199892)
			(end -4.800092 3.199892)
			(stroke
				(width 0.1)
				(type default)
			)
			(layer "F.Fab")
		)
		(pad "1" smd rect
			(at -3.350006 0 90)
			(size 3.0988 3.2004)
			(layers "F.Cu" "F.Mask" "F.Paste")
			(net "SW_PVCCFA_EHV_CPU1_SW1")
		)
		(pad "2" smd rect
			(at 3.350006 0 90)
			(size 3.0988 3.2004)
			(layers "F.Cu" "F.Mask" "F.Paste")
			(net "PVCCFA_EHV_CPU1")
		)
	)
	(footprint ""
		(layer "F.Cu")
		(at 51.593496 -113.72977)
		(property "Reference" "R3723"
			(at 0 0 0)
			(layer "F.SilkS")
			(hide yes)
			(effects
				(font
					(size 1.27 1.27)
				)
			)
		)
		(property "Value" ""
			(at 0 0 0)
			(layer "F.Fab")
			(effects
				(font
					(size 1.27 1.27)
				)
			)
		)
		(duplicate_pad_numbers_are_jumpers no)
		(fp_line
			(start -0.7874 -0.4064)
			(end 0.7874 -0.4064)
			(stroke
				(width 0.1524)
				(type default)
			)
			(layer "F.SilkS")
		)
		(fp_line
			(start -0.7874 0.4064)
			(end -0.7874 -0.4064)
			(stroke
				(width 0.1524)
				(type default)
			)
			(layer "F.SilkS")
		)
		(fp_line
			(start 0.7874 -0.4064)
			(end 0.7874 0.4064)
			(stroke
				(width 0.1524)
				(type default)
			)
			(layer "F.SilkS")
		)
		(fp_line
			(start 0.7874 0.4064)
			(end -0.7874 0.4064)
			(stroke
				(width 0.1524)
				(type default)
			)
			(layer "F.SilkS")
		)
		(fp_line
			(start -0.67945 -0.305054)
			(end -0.12065 -0.305054)
			(stroke
				(width 0.1)
				(type default)
			)
			(layer "F.Fab")
		)
		(fp_line
			(start -0.67945 0.3048)
			(end -0.67945 -0.305054)
			(stroke
				(width 0.1)
				(type default)
			)
			(layer "F.Fab")
		)
		(fp_line
			(start -0.12065 -0.305054)
			(end -0.12065 -0.2794)
			(stroke
				(width 0.1)
				(type default)
			)
			(layer "F.Fab")
		)
		(fp_line
			(start -0.12065 -0.2794)
			(end 0.12065 -0.2794)
			(stroke
				(width 0.1)
				(type default)
			)
			(layer "F.Fab")
		)
		(fp_line
			(start -0.12065 0.2794)
			(end -0.12065 0.3048)
			(stroke
				(width 0.1)
				(type default)
			)
			(layer "F.Fab")
		)
		(fp_line
			(start -0.12065 0.3048)
			(end -0.67945 0.3048)
			(stroke
				(width 0.1)
				(type default)
			)
			(layer "F.Fab")
		)
		(fp_line
			(start 0.120396 0.2794)
			(end -0.12065 0.2794)
			(stroke
				(width 0.1)
				(type default)
			)
			(layer "F.Fab")
		)
		(fp_line
			(start 0.120396 0.3048)
			(end 0.120396 0.2794)
			(stroke
				(width 0.1)
				(type default)
			)
			(layer "F.Fab")
		)
		(fp_line
			(start 0.12065 -0.3048)
			(end 0.67945 -0.3048)
			(stroke
				(width 0.1)
				(type default)
			)
			(layer "F.Fab")
		)
		(fp_line
			(start 0.12065 -0.2794)
			(end 0.12065 -0.3048)
			(stroke
				(width 0.1)
				(type default)
			)
			(layer "F.Fab")
		)
		(fp_line
			(start 0.67945 -0.3048)
			(end 0.67945 0.3048)
			(stroke
				(width 0.1)
				(type default)
			)
			(layer "F.Fab")
		)
		(fp_line
			(start 0.67945 0.3048)
			(end 0.120396 0.3048)
			(stroke
				(width 0.1)
				(type default)
			)
			(layer "F.Fab")
		)
		(pad "1" smd circle
			(at -0.40005 0)
			(size 0 0)
			(layers "F.Cu" "F.Mask" "F.Paste")
			(net "P3V3_AUX")
		)
		(pad "2" smd circle
			(at 0.40005 0)
			(size 0 0)
			(layers "F.Cu" "F.Mask" "F.Paste")
			(net "SMB_VR_3V3AUX_SCL")
		)
	)
	(footprint ""
		(layer "F.Cu")
		(at 182.58282 -419.47338 -90)
		(property "Reference" "R4796"
			(at 0 0 270)
			(layer "F.SilkS")
			(hide yes)
			(effects
				(font
					(size 1.27 1.27)
				)
			)
		)
		(property "Value" ""
			(at 0 0 270)
			(layer "F.Fab")
			(effects
				(font
					(size 1.27 1.27)
				)
			)
		)
		(duplicate_pad_numbers_are_jumpers no)
		(fp_line
			(start -0.7874 0.4064)
			(end -0.7874 -0.4064)
			(stroke
				(width 0.1524)
				(type default)
			)
			(layer "F.SilkS")
		)
		(fp_line
			(start 0.7874 0.4064)
			(end -0.7874 0.4064)
			(stroke
				(width 0.1524)
				(type default)
			)
			(layer "F.SilkS")
		)
		(fp_line
			(start -0.7874 -0.4064)
			(end 0.7874 -0.4064)
			(stroke
				(width 0.1524)
				(type default)
			)
			(layer "F.SilkS")
		)
		(fp_line
			(start 0.7874 -0.4064)
			(end 0.7874 0.4064)
			(stroke
				(width 0.1524)
				(type default)
			)
			(layer "F.SilkS")
		)
		(fp_line
			(start -0.67945 0.3048)
			(end -0.67945 -0.305054)
			(stroke
				(width 0.1)
				(type default)
			)
			(layer "F.Fab")
		)
		(fp_line
			(start -0.12065 0.3048)
			(end -0.67945 0.3048)
			(stroke
				(width 0.1)
				(type default)
			)
			(layer "F.Fab")
		)
		(fp_line
			(start 0.120396 0.3048)
			(end 0.120396 0.2794)
			(stroke
				(width 0.1)
				(type default)
			)
			(layer "F.Fab")
		)
		(fp_line
			(start 0.67945 0.3048)
			(end 0.120396 0.3048)
			(stroke
				(width 0.1)
				(type default)
			)
			(layer "F.Fab")
		)
		(fp_line
			(start -0.12065 0.2794)
			(end -0.12065 0.3048)
			(stroke
				(width 0.1)
				(type default)
			)
			(layer "F.Fab")
		)
		(fp_line
			(start 0.120396 0.2794)
			(end -0.12065 0.2794)
			(stroke
				(width 0.1)
				(type default)
			)
			(layer "F.Fab")
		)
		(fp_line
			(start -0.12065 -0.2794)
			(end 0.12065 -0.2794)
			(stroke
				(width 0.1)
				(type default)
			)
			(layer "F.Fab")
		)
		(fp_line
			(start 0.12065 -0.2794)
			(end 0.12065 -0.3048)
			(stroke
				(width 0.1)
				(type default)
			)
			(layer "F.Fab")
		)
		(fp_line
			(start 0.12065 -0.3048)
			(end 0.67945 -0.3048)
			(stroke
				(width 0.1)
				(type default)
			)
			(layer "F.Fab")
		)
		(fp_line
			(start 0.67945 -0.3048)
			(end 0.67945 0.3048)
			(stroke
				(width 0.1)
				(type default)
			)
			(layer "F.Fab")
		)
		(fp_line
			(start -0.67945 -0.305054)
			(end -0.12065 -0.305054)
			(stroke
				(width 0.1)
				(type default)
			)
			(layer "F.Fab")
		)
		(fp_line
			(start -0.12065 -0.305054)
			(end -0.12065 -0.2794)
			(stroke
				(width 0.1)
				(type default)
			)
			(layer "F.Fab")
		)
		(pad "1" smd circle
			(at -0.40005 0 270)
			(size 0 0)
			(layers "F.Cu" "F.Mask" "F.Paste")
			(net "HSC_OC_VOL")
		)
		(pad "2" smd circle
			(at 0.40005 0 270)
			(size 0 0)
			(layers "F.Cu" "F.Mask" "F.Paste")
			(net "GND")
		)
	)
)
